# S9S_MB_2U (Grand Teton) — schematic netlist excerpt (pin names and nets, part order shuffled) for the footprints in the layout excerpt that follows; sources: Cadence DE-HDL packaged netlist, KiCad conversion of 03242023_DA0F0TMBIJ0_F0T_Motherboard_J_brd_V01_OCP.brd

ME4  ME_DUMMY_SYMBOL  PICKUP_SMDC20 EMPTY  pkg PICKUP_SMDC20  page 312
R49  Q_RES  499 1% CHIP  pkg 0402LF  page 47 : A = PVNN_TERM_CPU1 ; B = DBP_CPU_MBP0_GTL_N
C41  Q_CAP  2.2UF 6.3V 20% X6S  pkg C0402  page 95 : A = P3V3_AUX ; B = GND

(kicad_pcb
	(version 20260206)
	(generator "pcbnew")
	(generator_version "10.0")
	(general
		(thickness 1.6)
		(legacy_teardrops no)
	)
	(paper "A4")
	(title_block
		(title "03242023_DA0F0TMBIJ0_F0T_Motherboard_J_brd_V01_OCP.brd")
		(comment 1 "Grand Teton / footprints 4192-4194 of 6105")
	)
	(layers
		(0 "F.Cu" signal "TOP")
		(4 "In1.Cu" signal "GND")
		(6 "In2.Cu" signal "IN1")
		(8 "In3.Cu" signal "GND1")
		(10 "In4.Cu" signal "IN2")
		(12 "In5.Cu" signal "GND2")
		(14 "In6.Cu" signal "IN3")
		(16 "In7.Cu" signal "GND3")
		(18 "In8.Cu" signal "VCC")
		(20 "In9.Cu" signal "VCC1")
		(22 "In10.Cu" signal "GND4")
		(24 "In11.Cu" signal "IN4")
		(26 "In12.Cu" signal "GND5")
		(28 "In13.Cu" signal "IN5")
		(30 "In14.Cu" signal "GND6")
		(32 "In15.Cu" signal "IN6")
		(34 "In16.Cu" signal "GND7")
		(2 "B.Cu" signal "BOTTOM")
		(9 "F.Adhes" user "F.Adhesive")
		(11 "B.Adhes" user "B.Adhesive")
		(13 "F.Paste" user "Package Geometry/Pastemask Top")
		(15 "B.Paste" user "Package Geometry/Pastemask Bottom")
		(5 "F.SilkS" user "Ref Des/Silkscreen Top")
		(7 "B.SilkS" user "Ref Des/Silkscreen Bottom")
		(1 "F.Mask" user "Board Geometry/Soldermask Top")
		(3 "B.Mask" user "Board Geometry/Soldermask Bottom")
		(17 "Dwgs.User" user "User.Drawings")
		(19 "Cmts.User" user "User.Comments")
		(21 "Eco1.User" user "User.Eco1")
		(23 "Eco2.User" user "User.Eco2")
		(25 "Edge.Cuts" user "Board Geometry/Outline")
		(27 "Margin" user)
		(31 "F.CrtYd" user "Package Geometry/Place Bound Top")
		(29 "B.CrtYd" user "Package Geometry/Place Bound Bottom")
		(35 "F.Fab" user "Ref Des/Assembly Top")
		(33 "B.Fab" user "Ref Des/Assembly Bottom")
	)
	(footprint ""
		(layer "B.Cu")
		(at 80.763618 -188.552836 -90)
		(property "Reference" "R49"
			(at 0 0 90)
			(layer "B.SilkS")
			(hide yes)
			(effects
				(font
					(size 1.27 1.27)
				)
				(justify mirror)
			)
		)
		(property "Value" ""
			(at 0 0 90)
			(layer "B.Fab")
			(effects
				(font
					(size 1.27 1.27)
				)
				(justify mirror)
			)
		)
		(duplicate_pad_numbers_are_jumpers no)
		(fp_line
			(start -0.7874 0.4064)
			(end 0.7874 0.4064)
			(stroke
				(width 0.1524)
				(type default)
			)
			(layer "B.SilkS")
		)
		(fp_line
			(start 0.7874 0.4064)
			(end 0.7874 -0.4064)
			(stroke
				(width 0.1524)
				(type default)
			)
			(layer "B.SilkS")
		)
		(fp_line
			(start -0.7874 -0.4064)
			(end -0.7874 0.4064)
			(stroke
				(width 0.1524)
				(type default)
			)
			(layer "B.SilkS")
		)
		(fp_line
			(start 0.7874 -0.4064)
			(end -0.7874 -0.4064)
			(stroke
				(width 0.1524)
				(type default)
			)
			(layer "B.SilkS")
		)
		(fp_line
			(start -0.67945 0.3048)
			(end -0.120396 0.3048)
			(stroke
				(width 0.1)
				(type default)
			)
			(layer "B.Fab")
		)
		(fp_line
			(start -0.120396 0.3048)
			(end -0.120396 0.2794)
			(stroke
				(width 0.1)
				(type default)
			)
			(layer "B.Fab")
		)
		(fp_line
			(start 0.12065 0.3048)
			(end 0.67945 0.3048)
			(stroke
				(width 0.1)
				(type default)
			)
			(layer "B.Fab")
		)
		(fp_line
			(start 0.67945 0.3048)
			(end 0.67945 -0.305054)
			(stroke
				(width 0.1)
				(type default)
			)
			(layer "B.Fab")
		)
		(fp_line
			(start -0.120396 0.2794)
			(end 0.12065 0.2794)
			(stroke
				(width 0.1)
				(type default)
			)
			(layer "B.Fab")
		)
		(fp_line
			(start 0.12065 0.2794)
			(end 0.12065 0.3048)
			(stroke
				(width 0.1)
				(type default)
			)
			(layer "B.Fab")
		)
		(fp_line
			(start -0.12065 -0.2794)
			(end -0.12065 -0.3048)
			(stroke
				(width 0.1)
				(type default)
			)
			(layer "B.Fab")
		)
		(fp_line
			(start 0.12065 -0.2794)
			(end -0.12065 -0.2794)
			(stroke
				(width 0.1)
				(type default)
			)
			(layer "B.Fab")
		)
		(fp_line
			(start -0.67945 -0.3048)
			(end -0.67945 0.3048)
			(stroke
				(width 0.1)
				(type default)
			)
			(layer "B.Fab")
		)
		(fp_line
			(start -0.12065 -0.3048)
			(end -0.67945 -0.3048)
			(stroke
				(width 0.1)
				(type default)
			)
			(layer "B.Fab")
		)
		(fp_line
			(start 0.12065 -0.305054)
			(end 0.12065 -0.2794)
			(stroke
				(width 0.1)
				(type default)
			)
			(layer "B.Fab")
		)
		(fp_line
			(start 0.67945 -0.305054)
			(end 0.12065 -0.305054)
			(stroke
				(width 0.1)
				(type default)
			)
			(layer "B.Fab")
		)
		(pad "1" smd circle
			(at 0.40005 0 90)
			(size 0 0)
			(layers "B.Cu" "B.Mask" "B.Paste")
			(net "PVNN_TERM_CPU1")
		)
		(pad "2" smd circle
			(at -0.40005 0 90)
			(size 0 0)
			(layers "B.Cu" "B.Mask" "B.Paste")
			(net "DBP_CPU_MBP0_GTL_N")
		)
	)
	(footprint ""
		(layer "B.Cu")
		(at 436.941214 -319.263776 180)
		(property "Reference" "C41"
			(at 0 0 0)
			(layer "B.SilkS")
			(hide yes)
			(effects
				(font
					(size 1.27 1.27)
				)
				(justify mirror)
			)
		)
		(property "Value" ""
			(at 0 0 0)
			(layer "B.Fab")
			(effects
				(font
					(size 1.27 1.27)
				)
				(justify mirror)
			)
		)
		(duplicate_pad_numbers_are_jumpers no)
		(fp_line
			(start 0.7874 0.4064)
			(end 0.7874 -0.4064)
			(stroke
				(width 0.1524)
				(type default)
			)
			(layer "B.SilkS")
		)
		(fp_line
			(start 0.7874 -0.4064)
			(end -0.7874 -0.4064)
			(stroke
				(width 0.1524)
				(type default)
			)
			(layer "B.SilkS")
		)
		(fp_line
			(start -0.7874 0.4064)
			(end 0.7874 0.4064)
			(stroke
				(width 0.1524)
				(type default)
			)
			(layer "B.SilkS")
		)
		(fp_line
			(start -0.7874 -0.4064)
			(end -0.7874 0.4064)
			(stroke
				(width 0.1524)
				(type default)
			)
			(layer "B.SilkS")
		)
		(fp_line
			(start 0.67945 0.3048)
			(end 0.67945 -0.305054)
			(stroke
				(width 0.1)
				(type default)
			)
			(layer "B.Fab")
		)
		(fp_line
			(start 0.67945 -0.305054)
			(end 0.12065 -0.305054)
			(stroke
				(width 0.1)
				(type default)
			)
			(layer "B.Fab")
		)
		(fp_line
			(start 0.12065 0.3048)
			(end 0.67945 0.3048)
			(stroke
				(width 0.1)
				(type default)
			)
			(layer "B.Fab")
		)
		(fp_line
			(start 0.12065 0.2794)
			(end 0.12065 0.3048)
			(stroke
				(width 0.1)
				(type default)
			)
			(layer "B.Fab")
		)
		(fp_line
			(start 0.12065 -0.2794)
			(end -0.12065 -0.2794)
			(stroke
				(width 0.1)
				(type default)
			)
			(layer "B.Fab")
		)
		(fp_line
			(start 0.12065 -0.305054)
			(end 0.12065 -0.2794)
			(stroke
				(width 0.1)
				(type default)
			)
			(layer "B.Fab")
		)
		(fp_line
			(start -0.120396 0.3048)
			(end -0.120396 0.2794)
			(stroke
				(width 0.1)
				(type default)
			)
			(layer "B.Fab")
		)
		(fp_line
			(start -0.120396 0.2794)
			(end 0.12065 0.2794)
			(stroke
				(width 0.1)
				(type default)
			)
			(layer "B.Fab")
		)
		(fp_line
			(start -0.12065 -0.2794)
			(end -0.12065 -0.3048)
			(stroke
				(width 0.1)
				(type default)
			)
			(layer "B.Fab")
		)
		(fp_line
			(start -0.12065 -0.3048)
			(end -0.67945 -0.3048)
			(stroke
				(width 0.1)
				(type default)
			)
			(layer "B.Fab")
		)
		(fp_line
			(start -0.67945 0.3048)
			(end -0.120396 0.3048)
			(stroke
				(width 0.1)
				(type default)
			)
			(layer "B.Fab")
		)
		(fp_line
			(start -0.67945 -0.3048)
			(end -0.67945 0.3048)
			(stroke
				(width 0.1)
				(type default)
			)
			(layer "B.Fab")
		)
		(pad "1" smd circle
			(at 0.40005 0)
			(size 0 0)
			(layers "B.Cu" "B.Mask" "B.Paste")
			(net "P3V3_AUX")
		)
		(pad "2" smd circle
			(at -0.40005 0)
			(size 0 0)
			(layers "B.Cu" "B.Mask" "B.Paste")
			(net "GND")
		)
	)
	(footprint ""
		(layer "B.Cu")
		(at 407.91892 -35.187128)
		(property "Reference" "ME4"
			(at 9.652 -9.540748 0)
			(unlocked yes)
			(layer "B.SilkS")
			(effects
				(font
					(size 0.7874 0.5842)
					(thickness 0.1524)
				)
				(justify left mirror)
			)
		)
		(property "Value" ""
			(at 0 0 0)
			(layer "B.Fab")
			(effects
				(font
					(size 1.27 1.27)
				)
				(justify mirror)
			)
		)
		(duplicate_pad_numbers_are_jumpers no)
	)
)
